(kicad_pcb
	(version 20241229)
	(generator "pcbnew")
	(generator_version "9.0")
	(general
		(thickness 1.6296)
		(legacy_teardrops no)
	)
	(paper "A3")
	(title_block
		(title "Thunderbolt to 10GbE adapter")
		(date "2026-04-21")
		(rev "1.1.0")
		(company "Antmicro Ltd")
		(comment 1 "www.antmicro.com")
		(comment 9 "footprints 468-472 of 703")
	)
	(layers
		(0 "F.Cu" signal)
		(4 "In1.Cu" signal)
		(6 "In2.Cu" signal)
		(8 "In3.Cu" signal)
		(10 "In4.Cu" signal)
		(12 "In5.Cu" signal)
		(14 "In6.Cu" signal)
		(2 "B.Cu" signal)
		(9 "F.Adhes" user "F.Adhesive")
		(11 "B.Adhes" user "B.Adhesive")
		(13 "F.Paste" user)
		(15 "B.Paste" user)
		(5 "F.SilkS" user "F.Silkscreen")
		(7 "B.SilkS" user "B.Silkscreen")
		(1 "F.Mask" user)
		(3 "B.Mask" user)
		(17 "Dwgs.User" user "User.Drawings")
		(19 "Cmts.User" user "User.Comments")
		(21 "Eco1.User" user "User.Eco1")
		(23 "Eco2.User" user "User.Eco2")
		(25 "Edge.Cuts" user)
		(27 "Margin" user)
		(31 "F.CrtYd" user "F.Courtyard")
		(29 "B.CrtYd" user "B.Courtyard")
		(35 "F.Fab" user)
		(33 "B.Fab" user)
	)
	(footprint "antmicro-footprints:C_0402_1005Metric"
		(layer "B.Cu")
		(at 149.325897 77.260117 180)
		(descr "Capacitor SMD 0402")
		(tags "capacitor SMD 0402")
		(property "Reference" "C237"
			(at -19.468135 -9.464883 0)
			(layer "B.SilkS")
			(effects
				(font
					(size 0.7 0.7)
					(thickness 0.15)
				)
				(justify mirror)
			)
		)
		(property "Value" "C_1u_25V_0402"
			(at -1.022927 -2.155213 0)
			(layer "B.Fab")
			(effects
				(font
					(size 0.7 0.7)
					(thickness 0.15)
				)
				(justify left bottom mirror)
			)
		)
		(property "Datasheet" "https://www.murata.com/products/productdetail?partno=GRM155R61E105KE11%23"
			(at 0 0 0)
			(layer "B.Fab")
			(hide yes)
			(effects
				(font
					(size 1.27 1.27)
					(thickness 0.15)
				)
				(justify mirror)
			)
		)
		(property "Description" "SMD Multilayer Ceramic Capacitor, 1 µF, 25 V, 0402 [1005 Metric], ± 10%, X5R, GRM Series"
			(at 0 0 0)
			(layer "B.Fab")
			(hide yes)
			(effects
				(font
					(size 1.27 1.27)
					(thickness 0.15)
				)
				(justify mirror)
			)
		)
		(property "MPN" "GRM155R61E105KE11J"
			(at 0 0 180)
			(unlocked yes)
			(layer "B.Fab")
			(hide yes)
			(effects
				(font
					(size 1 1)
					(thickness 0.15)
				)
				(justify mirror)
			)
		)
		(property "Manufacturer" "Murata"
			(at 0 0 180)
			(unlocked yes)
			(layer "B.Fab")
			(hide yes)
			(effects
				(font
					(size 1 1)
					(thickness 0.15)
				)
				(justify mirror)
			)
		)
		(property "License" "Apache-2.0"
			(at 0 0 180)
			(unlocked yes)
			(layer "B.Fab")
			(hide yes)
			(effects
				(font
					(size 1 1)
					(thickness 0.15)
				)
				(justify mirror)
			)
		)
		(property "Author" "Antmicro"
			(at 0 0 180)
			(unlocked yes)
			(layer "B.Fab")
			(hide yes)
			(effects
				(font
					(size 1 1)
					(thickness 0.15)
				)
				(justify mirror)
			)
		)
		(property "Val" "1u"
			(at 0 0 180)
			(unlocked yes)
			(layer "B.Fab")
			(hide yes)
			(effects
				(font
					(size 1 1)
					(thickness 0.15)
				)
				(justify mirror)
			)
		)
		(property "Voltage" "25V"
			(at 0 0 180)
			(unlocked yes)
			(layer "B.Fab")
			(hide yes)
			(effects
				(font
					(size 1 1)
					(thickness 0.15)
				)
				(justify mirror)
			)
		)
		(property "Dielectric" "X5R"
			(at 0 0 180)
			(unlocked yes)
			(layer "B.Fab")
			(hide yes)
			(effects
				(font
					(size 1 1)
					(thickness 0.15)
				)
				(justify mirror)
			)
		)
		(sheetname "/X710-AT2 power/")
		(sheetfile "x710-at2-power.kicad_sch")
		(attr smd)
		(fp_rect
			(start -0.925 0.47)
			(end 0.925 -0.47)
			(stroke
				(width 0.05)
				(type default)
			)
			(fill no)
			(layer "B.CrtYd")
		)
		(fp_line
			(start 0.504 0.25)
			(end 0.504 -0.248)
			(stroke
				(width 0.15)
				(type solid)
			)
			(layer "B.Fab")
		)
		(fp_line
			(start 0.504 -0.248)
			(end -0.494 -0.248)
			(stroke
				(width 0.15)
				(type solid)
			)
			(layer "B.Fab")
		)
		(fp_line
			(start -0.494 0.25)
			(end 0.504 0.25)
			(stroke
				(width 0.15)
				(type solid)
			)
			(layer "B.Fab")
		)
		(fp_line
			(start -0.494 -0.248)
			(end -0.494 0.25)
			(stroke
				(width 0.15)
				(type solid)
			)
			(layer "B.Fab")
		)
		(fp_text user "License: Apache-2.0"
			(at -0.939 -5.799 0)
			(layer "B.Fab")
			(effects
				(font
					(size 0.7 0.7)
					(thickness 0.15)
				)
				(justify left bottom mirror)
			)
		)
		(fp_text user "${REFERENCE}"
			(at -0.939 -4.599 0)
			(layer "B.Fab")
			(effects
				(font
					(size 0.7 0.7)
					(thickness 0.15)
				)
				(justify left bottom mirror)
			)
		)
		(fp_text user "Author: Antmicro"
			(at -0.939 -3.399 0)
			(layer "B.Fab")
			(effects
				(font
					(size 0.7 0.7)
					(thickness 0.15)
				)
				(justify left bottom mirror)
			)
		)
		(pad "1" smd roundrect
			(at -0.48 0 180)
			(size 0.59 0.64)
			(layers "B.Cu" "B.Mask" "B.Paste")
			(roundrect_rratio 0.25)
			(net 23 "GND")
			(pintype "passive")
		)
		(pad "2" smd roundrect
			(at 0.48 0 180)
			(size 0.59 0.64)
			(layers "B.Cu" "B.Mask" "B.Paste")
			(roundrect_rratio 0.25)
			(net 9 "VCCD")
			(pintype "passive")
		)
	)
	(footprint "antmicro-footprints:C_0402_1005Metric"
		(layer "B.Cu")
		(at 137.35 133.599998 180)
		(descr "Capacitor SMD 0402")
		(tags "capacitor SMD 0402")
		(property "Reference" "C14"
			(at -19.525001 8.1 0)
			(layer "B.SilkS")
			(effects
				(font
					(size 0.7 0.7)
					(thickness 0.15)
				)
				(justify mirror)
			)
		)
		(property "Value" "C_1u_0402"
			(at -1.022927 -2.155213 0)
			(layer "B.Fab")
			(effects
				(font
					(size 0.7 0.7)
					(thickness 0.15)
				)
				(justify left bottom mirror)
			)
		)
		(property "Datasheet" "https://product.tdk.com/en/search/capacitor/ceramic/mlcc/info?part_no=C1005X6S1A105K050BC"
			(at 0 0 0)
			(layer "B.Fab")
			(hide yes)
			(effects
				(font
					(size 1.27 1.27)
					(thickness 0.15)
				)
				(justify mirror)
			)
		)
		(property "Description" "SMD Multilayer Ceramic Capacitor, 1 µF, 10 V, 0402 [1005 Metric], ± 10%, X6S, C"
			(at 0 0 0)
			(layer "B.Fab")
			(hide yes)
			(effects
				(font
					(size 1.27 1.27)
					(thickness 0.15)
				)
				(justify mirror)
			)
		)
		(property "MPN" "C1005X6S1A105K050BC"
			(at 0 0 180)
			(unlocked yes)
			(layer "B.Fab")
			(hide yes)
			(effects
				(font
					(size 1 1)
					(thickness 0.15)
				)
				(justify mirror)
			)
		)
		(property "Manufacturer" "TDK"
			(at 0 0 180)
			(unlocked yes)
			(layer "B.Fab")
			(hide yes)
			(effects
				(font
					(size 1 1)
					(thickness 0.15)
				)
				(justify mirror)
			)
		)
		(property "License" "Apache-2.0"
			(at 0 0 180)
			(unlocked yes)
			(layer "B.Fab")
			(hide yes)
			(effects
				(font
					(size 1 1)
					(thickness 0.15)
				)
				(justify mirror)
			)
		)
		(property "Val" "1u"
			(at 0 0 180)
			(unlocked yes)
			(layer "B.Fab")
			(hide yes)
			(effects
				(font
					(size 1 1)
					(thickness 0.15)
				)
				(justify mirror)
			)
		)
		(property "Voltage" ""
			(at 0 0 180)
			(unlocked yes)
			(layer "B.Fab")
			(hide yes)
			(effects
				(font
					(size 1 1)
					(thickness 0.15)
				)
				(justify mirror)
			)
		)
		(property "Dielectric" ""
			(at 0 0 180)
			(unlocked yes)
			(layer "B.Fab")
			(hide yes)
			(effects
				(font
					(size 1 1)
					(thickness 0.15)
				)
				(justify mirror)
			)
		)
		(property "Author" "Antmicro"
			(at 0 0 180)
			(unlocked yes)
			(layer "B.Fab")
			(hide yes)
			(effects
				(font
					(size 1 1)
					(thickness 0.15)
				)
				(justify mirror)
			)
		)
		(sheetname "/PD and TB DC-DC/")
		(sheetfile "PD_and_TB_DC_DC.kicad_sch")
		(attr smd)
		(fp_rect
			(start -0.925 0.47)
			(end 0.925 -0.47)
			(stroke
				(width 0.05)
				(type default)
			)
			(fill no)
			(layer "B.CrtYd")
		)
		(fp_line
			(start 0.504 0.25)
			(end 0.504 -0.248)
			(stroke
				(width 0.15)
				(type solid)
			)
			(layer "B.Fab")
		)
		(fp_line
			(start 0.504 -0.248)
			(end -0.494 -0.248)
			(stroke
				(width 0.15)
				(type solid)
			)
			(layer "B.Fab")
		)
		(fp_line
			(start -0.494 0.25)
			(end 0.504 0.25)
			(stroke
				(width 0.15)
				(type solid)
			)
			(layer "B.Fab")
		)
		(fp_line
			(start -0.494 -0.248)
			(end -0.494 0.25)
			(stroke
				(width 0.15)
				(type solid)
			)
			(layer "B.Fab")
		)
		(fp_text user "${REFERENCE}"
			(at -0.939 -4.599 0)
			(layer "B.Fab")
			(effects
				(font
					(size 0.7 0.7)
					(thickness 0.15)
				)
				(justify left bottom mirror)
			)
		)
		(fp_text user "Author: Antmicro"
			(at -0.939 -3.399 0)
			(layer "B.Fab")
			(effects
				(font
					(size 0.7 0.7)
					(thickness 0.15)
				)
				(justify left bottom mirror)
			)
		)
		(fp_text user "License: Apache-2.0"
			(at -0.939 -5.799 0)
			(layer "B.Fab")
			(effects
				(font
					(size 0.7 0.7)
					(thickness 0.15)
				)
				(justify left bottom mirror)
			)
		)
		(pad "1" smd roundrect
			(at -0.48 0 180)
			(size 0.59 0.64)
			(layers "B.Cu" "B.Mask" "B.Paste")
			(roundrect_rratio 0.25)
			(net 23 "GND")
			(pintype "passive")
		)
		(pad "2" smd roundrect
			(at 0.48 0 180)
			(size 0.59 0.64)
			(layers "B.Cu" "B.Mask" "B.Paste")
			(roundrect_rratio 0.25)
			(net 57 "+3V3_TB")
			(pintype "passive")
		)
	)
	(footprint "antmicro-footprints:C_0402_1005Metric"
		(layer "B.Cu")
		(at 173.58 146.66 -90)
		(descr "Capacitor SMD 0402")
		(tags "capacitor SMD 0402")
		(property "Reference" "C305"
			(at 1.09 -0.42 90)
			(layer "B.SilkS")
			(effects
				(font
					(size 0.7 0.7)
					(thickness 0.15)
				)
				(justify left bottom mirror)
			)
		)
		(property "Value" "C_470p_0402"
			(at -1.022927 -2.155213 90)
			(layer "B.Fab")
			(effects
				(font
					(size 0.7 0.7)
					(thickness 0.15)
				)
				(justify left bottom mirror)
			)
		)
		(property "Datasheet" "https://www.passivecomponent.com/wp-content/uploads/datasheet/WTC_MLCC_General_Purpose.pdf"
			(at 0 0 90)
			(layer "B.Fab")
			(hide yes)
			(effects
				(font
					(size 1.27 1.27)
					(thickness 0.15)
				)
				(justify mirror)
			)
		)
		(property "Description" "SMD Multilayer Ceramic Capacitor, General Purpose, 470 pF, 25 V, 0402 [1005 Metric], ± 10%, X7R"
			(at 0 0 90)
			(layer "B.Fab")
			(hide yes)
			(effects
				(font
					(size 1.27 1.27)
					(thickness 0.15)
				)
				(justify mirror)
			)
		)
		(property "MPN" "0402B471K250CT"
			(at 0 0 270)
			(unlocked yes)
			(layer "B.Fab")
			(hide yes)
			(effects
				(font
					(size 1 1)
					(thickness 0.15)
				)
				(justify mirror)
			)
		)
		(property "Manufacturer" "Walsin"
			(at 0 0 270)
			(unlocked yes)
			(layer "B.Fab")
			(hide yes)
			(effects
				(font
					(size 1 1)
					(thickness 0.15)
				)
				(justify mirror)
			)
		)
		(property "License" "Apache-2.0"
			(at 0 0 270)
			(unlocked yes)
			(layer "B.Fab")
			(hide yes)
			(effects
				(font
					(size 1 1)
					(thickness 0.15)
				)
				(justify mirror)
			)
		)
		(property "Author" "Antmicro"
			(at 0 0 270)
			(unlocked yes)
			(layer "B.Fab")
			(hide yes)
			(effects
				(font
					(size 1 1)
					(thickness 0.15)
				)
				(justify mirror)
			)
		)
		(property "Val" "470p"
			(at 0 0 270)
			(unlocked yes)
			(layer "B.Fab")
			(hide yes)
			(effects
				(font
					(size 1 1)
					(thickness 0.15)
				)
				(justify mirror)
			)
		)
		(property "Voltage" "25V"
			(at 0 0 270)
			(unlocked yes)
			(layer "B.Fab")
			(hide yes)
			(effects
				(font
					(size 1 1)
					(thickness 0.15)
				)
				(justify mirror)
			)
		)
		(property "Dielectric" "X7R"
			(at 0 0 270)
			(unlocked yes)
			(layer "B.Fab")
			(hide yes)
			(effects
				(font
					(size 1 1)
					(thickness 0.15)
				)
				(justify mirror)
			)
		)
		(sheetname "/2xRJ45/")
		(sheetfile "2xrj45.kicad_sch")
		(attr smd)
		(fp_rect
			(start -0.925 0.47)
			(end 0.925 -0.47)
			(stroke
				(width 0.05)
				(type default)
			)
			(fill no)
			(layer "B.CrtYd")
		)
		(fp_line
			(start -0.494 0.25)
			(end 0.504 0.25)
			(stroke
				(width 0.15)
				(type solid)
			)
			(layer "B.Fab")
		)
		(fp_line
			(start 0.504 0.25)
			(end 0.504 -0.248)
			(stroke
				(width 0.15)
				(type solid)
			)
			(layer "B.Fab")
		)
		(fp_line
			(start -0.494 -0.248)
			(end -0.494 0.25)
			(stroke
				(width 0.15)
				(type solid)
			)
			(layer "B.Fab")
		)
		(fp_line
			(start 0.504 -0.248)
			(end -0.494 -0.248)
			(stroke
				(width 0.15)
				(type solid)
			)
			(layer "B.Fab")
		)
		(fp_text user "License: Apache-2.0"
			(at -0.939 -5.799 90)
			(layer "B.Fab")
			(effects
				(font
					(size 0.7 0.7)
					(thickness 0.15)
				)
				(justify left bottom mirror)
			)
		)
		(fp_text user "${REFERENCE}"
			(at -0.939 -4.599 90)
			(layer "B.Fab")
			(effects
				(font
					(size 0.7 0.7)
					(thickness 0.15)
				)
				(justify left bottom mirror)
			)
		)
		(fp_text user "Author: Antmicro"
			(at -0.939 -3.399 90)
			(layer "B.Fab")
			(effects
				(font
					(size 0.7 0.7)
					(thickness 0.15)
				)
				(justify left bottom mirror)
			)
		)
		(pad "1" smd roundrect
			(at -0.48 0 270)
			(size 0.59 0.64)
			(layers "B.Cu" "B.Mask" "B.Paste")
			(roundrect_rratio 0.25)
			(net 23 "GND")
			(pintype "passive")
		)
		(pad "2" smd roundrect
			(at 0.48 0 270)
			(size 0.59 0.64)
			(layers "B.Cu" "B.Mask" "B.Paste")
			(roundrect_rratio 0.25)
			(net 409 "Net-(J4-LED_YG_G-)")
			(pintype "passive")
		)
	)
	(footprint "antmicro-footprints:Fiducial_1mm_Mask2mm"
		(layer "B.Cu")
		(at 125 47.5 180)
		(descr "Circular Fiducial, 1mm bare copper, 3mm soldermask opening")
		(tags "fiducial")
		(property "Reference" "FD2"
			(at -1 -2.7 0)
			(layer "B.SilkS")
			(effects
				(font
					(size 0.7 0.7)
					(thickness 0.15)
				)
				(justify left bottom mirror)
			)
		)
		(property "Value" "Fiducial_1mm_Mask2mm"
			(at 0 -2.2 0)
			(layer "B.Fab")
			(effects
				(font
					(size 0.7 0.7)
					(thickness 0.15)
				)
				(justify left bottom mirror)
			)
		)
		(property "Description" "Fiducial mask"
			(at 0 0 0)
			(layer "B.Fab")
			(hide yes)
			(effects
				(font
					(size 1.27 1.27)
					(thickness 0.15)
				)
				(justify mirror)
			)
		)
		(property "Author" "Antmicro"
			(at 0 0 180)
			(unlocked yes)
			(layer "B.Fab")
			(hide yes)
			(effects
				(font
					(size 1 1)
					(thickness 0.15)
				)
				(justify mirror)
			)
		)
		(property "License" "Apache-2.0"
			(at 0 0 180)
			(unlocked yes)
			(layer "B.Fab")
			(hide yes)
			(effects
				(font
					(size 1 1)
					(thickness 0.15)
				)
				(justify mirror)
			)
		)
		(sheetname "/")
		(sheetfile "thunderbolt-to-10gbe-adapter.kicad_sch")
		(attr exclude_from_pos_files exclude_from_bom)
		(fp_circle
			(center 0 0)
			(end 1.24 0)
			(stroke
				(width 0.05)
				(type solid)
			)
			(fill no)
			(layer "B.CrtYd")
		)
		(fp_circle
			(center 0 0)
			(end 0.999 0)
			(stroke
				(width 0.15)
				(type solid)
			)
			(fill no)
			(layer "B.Fab")
		)
		(fp_text user "License: Apache-2.0"
			(at -1.25 -7.003 0)
			(layer "B.Fab")
			(effects
				(font
					(size 0.7 0.7)
					(thickness 0.15)
				)
				(justify left bottom mirror)
			)
		)
		(fp_text user "Author: Antmicro"
			(at -1.25 -5.803 0)
			(layer "B.Fab")
			(effects
				(font
					(size 0.7 0.7)
					(thickness 0.15)
				)
				(justify left bottom mirror)
			)
		)
		(fp_text user "${REFERENCE}"
			(at -1.25 -4.603 0)
			(layer "B.Fab")
			(effects
				(font
					(size 0.7 0.7)
					(thickness 0.15)
				)
				(justify left bottom mirror)
			)
		)
		(pad "" smd circle
			(at 0 0 180)
			(size 1 1)
			(layers "B.Cu" "B.Mask")
			(solder_mask_margin 0.5)
			(clearance 0.5)
		)
	)
	(footprint "antmicro-footprints:R_0402_1005Metric"
		(layer "B.Cu")
		(at 139.2 131.6 180)
		(descr "Resistor SMD 0402")
		(tags "resistor SMD 0402")
		(property "Reference" "R10"
			(at -19.525001 8.1 0)
			(layer "B.SilkS")
			(effects
				(font
					(size 0.7 0.7)
					(thickness 0.15)
				)
				(justify mirror)
			)
		)
		(property "Value" "R_2k2_0402"
			(at -1.011843 -1.772047 0)
			(layer "B.Fab")
			(effects
				(font
					(size 0.7 0.7)
					(thickness 0.15)
				)
				(justify left bottom mirror)
			)
		)
		(property "Datasheet" "https://www.bourns.com/docs/product-datasheets/cr.pdf"
			(at 0 0 0)
			(layer "B.Fab")
			(hide yes)
			(effects
				(font
					(size 1.27 1.27)
					(thickness 0.15)
				)
				(justify mirror)
			)
		)
		(property "Description" "SMD Chip Resistor, 2.2 kohm, ± 1%, 62.5 mW, 0402 [1005 Metric], Thick Film, General Purpose"
			(at 0 0 0)
			(layer "B.Fab")
			(hide yes)
			(effects
				(font
					(size 1.27 1.27)
					(thickness 0.15)
				)
				(justify mirror)
			)
		)
		(property "MPN" "CR0402-FX-2201GLF"
			(at 0 0 180)
			(unlocked yes)
			(layer "B.Fab")
			(hide yes)
			(effects
				(font
					(size 1 1)
					(thickness 0.15)
				)
				(justify mirror)
			)
		)
		(property "Manufacturer" "Bourns"
			(at 0 0 180)
			(unlocked yes)
			(layer "B.Fab")
			(hide yes)
			(effects
				(font
					(size 1 1)
					(thickness 0.15)
				)
				(justify mirror)
			)
		)
		(property "License" "Apache-2.0"
			(at 0 0 180)
			(unlocked yes)
			(layer "B.Fab")
			(hide yes)
			(effects
				(font
					(size 1 1)
					(thickness 0.15)
				)
				(justify mirror)
			)
		)
		(property "Val" "2k2"
			(at 0 0 180)
			(unlocked yes)
			(layer "B.Fab")
			(hide yes)
			(effects
				(font
					(size 1 1)
					(thickness 0.15)
				)
				(justify mirror)
			)
		)
		(property "Tolerance" "1%"
			(at 0 0 180)
			(unlocked yes)
			(layer "B.Fab")
			(hide yes)
			(effects
				(font
					(size 1 1)
					(thickness 0.15)
				)
				(justify mirror)
			)
		)
		(property "Author" "Antmicro"
			(at 0 0 180)
			(unlocked yes)
			(layer "B.Fab")
			(hide yes)
			(effects
				(font
					(size 1 1)
					(thickness 0.15)
				)
				(justify mirror)
			)
		)
		(sheetname "/PD and TB DC-DC/")
		(sheetfile "PD_and_TB_DC_DC.kicad_sch")
		(attr smd)
		(fp_rect
			(start -0.925 0.47)
			(end 0.925 -0.47)
			(stroke
				(width 0.05)
				(type default)
			)
			(fill no)
			(layer "B.CrtYd")
		)
		(fp_rect
			(start -0.5 0.25)
			(end 0.5 -0.25)
			(stroke
				(width 0.15)
				(type solid)
			)
			(fill no)
			(layer "B.Fab")
		)
		(fp_text user "${REFERENCE}"
			(at -0.95 -3.168 0)
			(layer "B.Fab")
			(effects
				(font
					(size 0.7 0.7)
					(thickness 0.15)
				)
				(justify left bottom mirror)
			)
		)
		(fp_text user "License: Apache-2.0"
			(at -0.95 -5.169 0)
			(layer "B.Fab")
			(effects
				(font
					(size 0.7 0.7)
					(thickness 0.15)
				)
				(justify left bottom mirror)
			)
		)
		(fp_text user "Author: Antmicro"
			(at -0.95 -4.169 0)
			(layer "B.Fab")
			(effects
				(font
					(size 0.7 0.7)
					(thickness 0.15)
				)
				(justify left bottom mirror)
			)
		)
		(pad "1" smd roundrect
			(at -0.48 0 180)
			(size 0.59 0.64)
			(layers "B.Cu" "B.Mask" "B.Paste")
			(roundrect_rratio 0.25)
			(net 375 "/PD and TB DC-DC/I2C1.SDA")
			(pintype "passive")
		)
		(pad "2" smd roundrect
			(at 0.48 0 180)
			(size 0.59 0.64)
			(layers "B.Cu" "B.Mask" "B.Paste")
			(roundrect_rratio 0.25)
			(net 57 "+3V3_TB")
			(pintype "passive")
		)
	)
)
